(kicad_pcb
	(version 20260206)
	(generator "pcbnew")
	(generator_version "10.0")
	(general
		(thickness 1.6)
		(legacy_teardrops no)
	)
	(paper "A4")
	(title_block
		(title "03242023_DA0F0TMBIJ0_F0T_Motherboard_J_brd_V01_OCP.brd")
		(comment 1 "Grand Teton / footprints 2429-2434 of 6105")
	)
	(layers
		(0 "F.Cu" signal "TOP")
		(4 "In1.Cu" signal "GND")
		(6 "In2.Cu" signal "IN1")
		(8 "In3.Cu" signal "GND1")
		(10 "In4.Cu" signal "IN2")
		(12 "In5.Cu" signal "GND2")
		(14 "In6.Cu" signal "IN3")
		(16 "In7.Cu" signal "GND3")
		(18 "In8.Cu" signal "VCC")
		(20 "In9.Cu" signal "VCC1")
		(22 "In10.Cu" signal "GND4")
		(24 "In11.Cu" signal "IN4")
		(26 "In12.Cu" signal "GND5")
		(28 "In13.Cu" signal "IN5")
		(30 "In14.Cu" signal "GND6")
		(32 "In15.Cu" signal "IN6")
		(34 "In16.Cu" signal "GND7")
		(2 "B.Cu" signal "BOTTOM")
		(9 "F.Adhes" user "F.Adhesive")
		(11 "B.Adhes" user "B.Adhesive")
		(13 "F.Paste" user "Package Geometry/Pastemask Top")
		(15 "B.Paste" user "Package Geometry/Pastemask Bottom")
		(5 "F.SilkS" user "Ref Des/Silkscreen Top")
		(7 "B.SilkS" user "Ref Des/Silkscreen Bottom")
		(1 "F.Mask" user "Board Geometry/Soldermask Top")
		(3 "B.Mask" user "Board Geometry/Soldermask Bottom")
		(17 "Dwgs.User" user "User.Drawings")
		(19 "Cmts.User" user "User.Comments")
		(21 "Eco1.User" user "User.Eco1")
		(23 "Eco2.User" user "User.Eco2")
		(25 "Edge.Cuts" user "Board Geometry/Outline")
		(27 "Margin" user)
		(31 "F.CrtYd" user "Package Geometry/Place Bound Top")
		(29 "B.CrtYd" user "Package Geometry/Place Bound Bottom")
		(35 "F.Fab" user "Ref Des/Assembly Top")
		(33 "B.Fab" user "Ref Des/Assembly Bottom")
	)
	(footprint ""
		(layer "F.Cu")
		(at 403.946106 -62.994032)
		(property "Reference" "R769"
			(at 0 0 0)
			(layer "F.SilkS")
			(hide yes)
			(effects
				(font
					(size 1.27 1.27)
				)
			)
		)
		(property "Value" ""
			(at 0 0 0)
			(layer "F.Fab")
			(effects
				(font
					(size 1.27 1.27)
				)
			)
		)
		(duplicate_pad_numbers_are_jumpers no)
		(fp_line
			(start -0.7874 -0.4064)
			(end 0.7874 -0.4064)
			(stroke
				(width 0.1524)
				(type default)
			)
			(layer "F.SilkS")
		)
		(fp_line
			(start -0.7874 0.4064)
			(end -0.7874 -0.4064)
			(stroke
				(width 0.1524)
				(type default)
			)
			(layer "F.SilkS")
		)
		(fp_line
			(start 0.7874 -0.4064)
			(end 0.7874 0.4064)
			(stroke
				(width 0.1524)
				(type default)
			)
			(layer "F.SilkS")
		)
		(fp_line
			(start 0.7874 0.4064)
			(end -0.7874 0.4064)
			(stroke
				(width 0.1524)
				(type default)
			)
			(layer "F.SilkS")
		)
		(fp_line
			(start -0.67945 -0.305054)
			(end -0.12065 -0.305054)
			(stroke
				(width 0.1)
				(type default)
			)
			(layer "F.Fab")
		)
		(fp_line
			(start -0.67945 0.3048)
			(end -0.67945 -0.305054)
			(stroke
				(width 0.1)
				(type default)
			)
			(layer "F.Fab")
		)
		(fp_line
			(start -0.12065 -0.305054)
			(end -0.12065 -0.2794)
			(stroke
				(width 0.1)
				(type default)
			)
			(layer "F.Fab")
		)
		(fp_line
			(start -0.12065 -0.2794)
			(end 0.12065 -0.2794)
			(stroke
				(width 0.1)
				(type default)
			)
			(layer "F.Fab")
		)
		(fp_line
			(start -0.12065 0.2794)
			(end -0.12065 0.3048)
			(stroke
				(width 0.1)
				(type default)
			)
			(layer "F.Fab")
		)
		(fp_line
			(start -0.12065 0.3048)
			(end -0.67945 0.3048)
			(stroke
				(width 0.1)
				(type default)
			)
			(layer "F.Fab")
		)
		(fp_line
			(start 0.120396 0.2794)
			(end -0.12065 0.2794)
			(stroke
				(width 0.1)
				(type default)
			)
			(layer "F.Fab")
		)
		(fp_line
			(start 0.120396 0.3048)
			(end 0.120396 0.2794)
			(stroke
				(width 0.1)
				(type default)
			)
			(layer "F.Fab")
		)
		(fp_line
			(start 0.12065 -0.3048)
			(end 0.67945 -0.3048)
			(stroke
				(width 0.1)
				(type default)
			)
			(layer "F.Fab")
		)
		(fp_line
			(start 0.12065 -0.2794)
			(end 0.12065 -0.3048)
			(stroke
				(width 0.1)
				(type default)
			)
			(layer "F.Fab")
		)
		(fp_line
			(start 0.67945 -0.3048)
			(end 0.67945 0.3048)
			(stroke
				(width 0.1)
				(type default)
			)
			(layer "F.Fab")
		)
		(fp_line
			(start 0.67945 0.3048)
			(end 0.120396 0.3048)
			(stroke
				(width 0.1)
				(type default)
			)
			(layer "F.Fab")
		)
		(pad "1" smd circle
			(at -0.40005 0)
			(size 0 0)
			(layers "F.Cu" "F.Mask" "F.Paste")
			(net "PD_TRST_P3")
		)
		(pad "2" smd circle
			(at 0.40005 0)
			(size 0 0)
			(layers "F.Cu" "F.Mask" "F.Paste")
			(net "GND")
		)
	)
	(footprint ""
		(layer "F.Cu")
		(at 410.41701 -408.517344 -90)
		(property "Reference" "C895"
			(at 0 0 270)
			(layer "F.SilkS")
			(hide yes)
			(effects
				(font
					(size 1.27 1.27)
				)
			)
		)
		(property "Value" ""
			(at 0 0 270)
			(layer "F.Fab")
			(effects
				(font
					(size 1.27 1.27)
				)
			)
		)
		(duplicate_pad_numbers_are_jumpers no)
		(fp_line
			(start -0.299974 0.150114)
			(end -0.299974 -0.150114)
			(stroke
				(width 0.1)
				(type default)
			)
			(layer "F.Fab")
		)
		(fp_line
			(start 0.299974 0.150114)
			(end -0.299974 0.150114)
			(stroke
				(width 0.1)
				(type default)
			)
			(layer "F.Fab")
		)
		(fp_line
			(start -0.299974 -0.150114)
			(end 0.299974 -0.150114)
			(stroke
				(width 0.1)
				(type default)
			)
			(layer "F.Fab")
		)
		(fp_line
			(start 0.299974 -0.150114)
			(end 0.299974 0.150114)
			(stroke
				(width 0.1)
				(type default)
			)
			(layer "F.Fab")
		)
		(pad "1" smd rect
			(at -0.2667 0 270)
			(size 0.3048 0.381)
			(layers "F.Cu" "F.Mask" "F.Paste")
			(net "P5E_CPU0_PE3_TX_C_DP<3>")
		)
		(pad "2" smd rect
			(at 0.2667 0 270)
			(size 0.3048 0.381)
			(layers "F.Cu" "F.Mask" "F.Paste")
			(net "P5E_CPU0_PE3_TX_DP<3>")
		)
	)
	(footprint ""
		(layer "F.Cu")
		(at 42.446194 -366.62106)
		(property "Reference" "PC1657"
			(at 0 0 0)
			(layer "F.SilkS")
			(hide yes)
			(effects
				(font
					(size 1.27 1.27)
				)
			)
		)
		(property "Value" ""
			(at 0 0 0)
			(layer "F.Fab")
			(effects
				(font
					(size 1.27 1.27)
				)
			)
		)
		(duplicate_pad_numbers_are_jumpers no)
		(fp_line
			(start -0.7874 -0.4064)
			(end 0.7874 -0.4064)
			(stroke
				(width 0.1524)
				(type default)
			)
			(layer "F.SilkS")
		)
		(fp_line
			(start -0.7874 0.4064)
			(end -0.7874 -0.4064)
			(stroke
				(width 0.1524)
				(type default)
			)
			(layer "F.SilkS")
		)
		(fp_line
			(start 0.7874 -0.4064)
			(end 0.7874 0.4064)
			(stroke
				(width 0.1524)
				(type default)
			)
			(layer "F.SilkS")
		)
		(fp_line
			(start 0.7874 0.4064)
			(end -0.7874 0.4064)
			(stroke
				(width 0.1524)
				(type default)
			)
			(layer "F.SilkS")
		)
		(fp_line
			(start -0.67945 -0.305054)
			(end -0.12065 -0.305054)
			(stroke
				(width 0.1)
				(type default)
			)
			(layer "F.Fab")
		)
		(fp_line
			(start -0.67945 0.3048)
			(end -0.67945 -0.305054)
			(stroke
				(width 0.1)
				(type default)
			)
			(layer "F.Fab")
		)
		(fp_line
			(start -0.12065 -0.305054)
			(end -0.12065 -0.2794)
			(stroke
				(width 0.1)
				(type default)
			)
			(layer "F.Fab")
		)
		(fp_line
			(start -0.12065 -0.2794)
			(end 0.12065 -0.2794)
			(stroke
				(width 0.1)
				(type default)
			)
			(layer "F.Fab")
		)
		(fp_line
			(start -0.12065 0.2794)
			(end -0.12065 0.3048)
			(stroke
				(width 0.1)
				(type default)
			)
			(layer "F.Fab")
		)
		(fp_line
			(start -0.12065 0.3048)
			(end -0.67945 0.3048)
			(stroke
				(width 0.1)
				(type default)
			)
			(layer "F.Fab")
		)
		(fp_line
			(start 0.120396 0.2794)
			(end -0.12065 0.2794)
			(stroke
				(width 0.1)
				(type default)
			)
			(layer "F.Fab")
		)
		(fp_line
			(start 0.120396 0.3048)
			(end 0.120396 0.2794)
			(stroke
				(width 0.1)
				(type default)
			)
			(layer "F.Fab")
		)
		(fp_line
			(start 0.12065 -0.3048)
			(end 0.67945 -0.3048)
			(stroke
				(width 0.1)
				(type default)
			)
			(layer "F.Fab")
		)
		(fp_line
			(start 0.12065 -0.2794)
			(end 0.12065 -0.3048)
			(stroke
				(width 0.1)
				(type default)
			)
			(layer "F.Fab")
		)
		(fp_line
			(start 0.67945 -0.3048)
			(end 0.67945 0.3048)
			(stroke
				(width 0.1)
				(type default)
			)
			(layer "F.Fab")
		)
		(fp_line
			(start 0.67945 0.3048)
			(end 0.120396 0.3048)
			(stroke
				(width 0.1)
				(type default)
			)
			(layer "F.Fab")
		)
		(pad "1" smd circle
			(at -0.40005 0)
			(size 0 0)
			(layers "F.Cu" "F.Mask" "F.Paste")
			(net "P12V_AUX")
		)
		(pad "2" smd circle
			(at 0.40005 0)
			(size 0 0)
			(layers "F.Cu" "F.Mask" "F.Paste")
			(net "GND")
		)
	)
	(footprint ""
		(layer "F.Cu")
		(at 172.77588 -133.695948 -90)
		(property "Reference" "R3047"
			(at 0 0 270)
			(layer "F.SilkS")
			(hide yes)
			(effects
				(font
					(size 1.27 1.27)
				)
			)
		)
		(property "Value" ""
			(at 0 0 270)
			(layer "F.Fab")
			(effects
				(font
					(size 1.27 1.27)
				)
			)
		)
		(duplicate_pad_numbers_are_jumpers no)
		(fp_line
			(start -0.7874 0.4064)
			(end -0.7874 -0.4064)
			(stroke
				(width 0.1524)
				(type default)
			)
			(layer "F.SilkS")
		)
		(fp_line
			(start 0.7874 0.4064)
			(end -0.7874 0.4064)
			(stroke
				(width 0.1524)
				(type default)
			)
			(layer "F.SilkS")
		)
		(fp_line
			(start -0.7874 -0.4064)
			(end 0.7874 -0.4064)
			(stroke
				(width 0.1524)
				(type default)
			)
			(layer "F.SilkS")
		)
		(fp_line
			(start 0.7874 -0.4064)
			(end 0.7874 0.4064)
			(stroke
				(width 0.1524)
				(type default)
			)
			(layer "F.SilkS")
		)
		(fp_line
			(start -0.67945 0.3048)
			(end -0.67945 -0.305054)
			(stroke
				(width 0.1)
				(type default)
			)
			(layer "F.Fab")
		)
		(fp_line
			(start -0.12065 0.3048)
			(end -0.67945 0.3048)
			(stroke
				(width 0.1)
				(type default)
			)
			(layer "F.Fab")
		)
		(fp_line
			(start 0.120396 0.3048)
			(end 0.120396 0.2794)
			(stroke
				(width 0.1)
				(type default)
			)
			(layer "F.Fab")
		)
		(fp_line
			(start 0.67945 0.3048)
			(end 0.120396 0.3048)
			(stroke
				(width 0.1)
				(type default)
			)
			(layer "F.Fab")
		)
		(fp_line
			(start -0.12065 0.2794)
			(end -0.12065 0.3048)
			(stroke
				(width 0.1)
				(type default)
			)
			(layer "F.Fab")
		)
		(fp_line
			(start 0.120396 0.2794)
			(end -0.12065 0.2794)
			(stroke
				(width 0.1)
				(type default)
			)
			(layer "F.Fab")
		)
		(fp_line
			(start -0.12065 -0.2794)
			(end 0.12065 -0.2794)
			(stroke
				(width 0.1)
				(type default)
			)
			(layer "F.Fab")
		)
		(fp_line
			(start 0.12065 -0.2794)
			(end 0.12065 -0.3048)
			(stroke
				(width 0.1)
				(type default)
			)
			(layer "F.Fab")
		)
		(fp_line
			(start 0.12065 -0.3048)
			(end 0.67945 -0.3048)
			(stroke
				(width 0.1)
				(type default)
			)
			(layer "F.Fab")
		)
		(fp_line
			(start 0.67945 -0.3048)
			(end 0.67945 0.3048)
			(stroke
				(width 0.1)
				(type default)
			)
			(layer "F.Fab")
		)
		(fp_line
			(start -0.67945 -0.305054)
			(end -0.12065 -0.305054)
			(stroke
				(width 0.1)
				(type default)
			)
			(layer "F.Fab")
		)
		(fp_line
			(start -0.12065 -0.305054)
			(end -0.12065 -0.2794)
			(stroke
				(width 0.1)
				(type default)
			)
			(layer "F.Fab")
		)
		(pad "1" smd circle
			(at -0.40005 0 270)
			(size 0 0)
			(layers "F.Cu" "F.Mask" "F.Paste")
			(net "MB0_P12V_STBY_PWRGD")
		)
		(pad "2" smd circle
			(at 0.40005 0 270)
			(size 0 0)
			(layers "F.Cu" "F.Mask" "F.Paste")
			(net "PWRGD_PS_PWROK_PLD")
		)
	)
	(footprint ""
		(layer "F.Cu")
		(at 69.917818 -25.192482)
		(property "Reference" "PC2174"
			(at 0 0 0)
			(layer "F.SilkS")
			(hide yes)
			(effects
				(font
					(size 1.27 1.27)
				)
			)
		)
		(property "Value" ""
			(at 0 0 0)
			(layer "F.Fab")
			(effects
				(font
					(size 1.27 1.27)
				)
			)
		)
		(duplicate_pad_numbers_are_jumpers no)
		(fp_line
			(start -0.7874 -0.4064)
			(end 0.7874 -0.4064)
			(stroke
				(width 0.1524)
				(type default)
			)
			(layer "F.SilkS")
		)
		(fp_line
			(start -0.7874 0.4064)
			(end -0.7874 -0.4064)
			(stroke
				(width 0.1524)
				(type default)
			)
			(layer "F.SilkS")
		)
		(fp_line
			(start 0.7874 -0.4064)
			(end 0.7874 0.4064)
			(stroke
				(width 0.1524)
				(type default)
			)
			(layer "F.SilkS")
		)
		(fp_line
			(start 0.7874 0.4064)
			(end -0.7874 0.4064)
			(stroke
				(width 0.1524)
				(type default)
			)
			(layer "F.SilkS")
		)
		(fp_line
			(start -0.67945 -0.305054)
			(end -0.12065 -0.305054)
			(stroke
				(width 0.1)
				(type default)
			)
			(layer "F.Fab")
		)
		(fp_line
			(start -0.67945 0.3048)
			(end -0.67945 -0.305054)
			(stroke
				(width 0.1)
				(type default)
			)
			(layer "F.Fab")
		)
		(fp_line
			(start -0.12065 -0.305054)
			(end -0.12065 -0.2794)
			(stroke
				(width 0.1)
				(type default)
			)
			(layer "F.Fab")
		)
		(fp_line
			(start -0.12065 -0.2794)
			(end 0.12065 -0.2794)
			(stroke
				(width 0.1)
				(type default)
			)
			(layer "F.Fab")
		)
		(fp_line
			(start -0.12065 0.2794)
			(end -0.12065 0.3048)
			(stroke
				(width 0.1)
				(type default)
			)
			(layer "F.Fab")
		)
		(fp_line
			(start -0.12065 0.3048)
			(end -0.67945 0.3048)
			(stroke
				(width 0.1)
				(type default)
			)
			(layer "F.Fab")
		)
		(fp_line
			(start 0.120396 0.2794)
			(end -0.12065 0.2794)
			(stroke
				(width 0.1)
				(type default)
			)
			(layer "F.Fab")
		)
		(fp_line
			(start 0.120396 0.3048)
			(end 0.120396 0.2794)
			(stroke
				(width 0.1)
				(type default)
			)
			(layer "F.Fab")
		)
		(fp_line
			(start 0.12065 -0.3048)
			(end 0.67945 -0.3048)
			(stroke
				(width 0.1)
				(type default)
			)
			(layer "F.Fab")
		)
		(fp_line
			(start 0.12065 -0.2794)
			(end 0.12065 -0.3048)
			(stroke
				(width 0.1)
				(type default)
			)
			(layer "F.Fab")
		)
		(fp_line
			(start 0.67945 -0.3048)
			(end 0.67945 0.3048)
			(stroke
				(width 0.1)
				(type default)
			)
			(layer "F.Fab")
		)
		(fp_line
			(start 0.67945 0.3048)
			(end 0.120396 0.3048)
			(stroke
				(width 0.1)
				(type default)
			)
			(layer "F.Fab")
		)
		(pad "1" smd circle
			(at -0.40005 0)
			(size 0 0)
			(layers "F.Cu" "F.Mask" "F.Paste")
			(net "P12V_OCP_V3_2")
		)
		(pad "2" smd circle
			(at 0.40005 0)
			(size 0 0)
			(layers "F.Cu" "F.Mask" "F.Paste")
			(net "GND")
		)
	)
	(footprint ""
		(layer "F.Cu")
		(at 101.046026 -357.126032 -90)
		(property "Reference" "C2448"
			(at 0 0 270)
			(layer "F.SilkS")
			(hide yes)
			(effects
				(font
					(size 1.27 1.27)
				)
			)
		)
		(property "Value" ""
			(at 0 0 270)
			(layer "F.Fab")
			(effects
				(font
					(size 1.27 1.27)
				)
			)
		)
		(duplicate_pad_numbers_are_jumpers no)
		(fp_line
			(start -1.2954 0.5842)
			(end -1.2954 -0.5842)
			(stroke
				(width 0.1524)
				(type default)
			)
			(layer "F.SilkS")
		)
		(fp_line
			(start 1.2954 0.5842)
			(end -1.2954 0.5842)
			(stroke
				(width 0.1524)
				(type default)
			)
			(layer "F.SilkS")
		)
		(fp_line
			(start -1.2954 -0.5842)
			(end 1.2954 -0.5842)
			(stroke
				(width 0.1524)
				(type default)
			)
			(layer "F.SilkS")
		)
		(fp_line
			(start 0 -0.5842)
			(end 0 0.5842)
			(stroke
				(width 0.1524)
				(type default)
			)
			(layer "F.SilkS")
		)
		(fp_line
			(start 1.2954 -0.5842)
			(end 1.2954 0.5842)
			(stroke
				(width 0.1524)
				(type default)
			)
			(layer "F.SilkS")
		)
		(fp_line
			(start -0.8636 0.4572)
			(end -0.8636 0.4064)
			(stroke
				(width 0.1)
				(type default)
			)
			(layer "F.Fab")
		)
		(fp_line
			(start 0.8636 0.4572)
			(end -0.8636 0.4572)
			(stroke
				(width 0.1)
				(type default)
			)
			(layer "F.Fab")
		)
		(fp_line
			(start -1.1938 0.4064)
			(end -1.1938 -0.4064)
			(stroke
				(width 0.1)
				(type default)
			)
			(layer "F.Fab")
		)
		(fp_line
			(start -0.8636 0.4064)
			(end -1.1938 0.4064)
			(stroke
				(width 0.1)
				(type default)
			)
			(layer "F.Fab")
		)
		(fp_line
			(start 0.8636 0.4064)
			(end 0.8636 0.4572)
			(stroke
				(width 0.1)
				(type default)
			)
			(layer "F.Fab")
		)
		(fp_line
			(start 1.1938 0.4064)
			(end 0.8636 0.4064)
			(stroke
				(width 0.1)
				(type default)
			)
			(layer "F.Fab")
		)
		(fp_line
			(start -1.1938 -0.4064)
			(end -0.8636 -0.4064)
			(stroke
				(width 0.1)
				(type default)
			)
			(layer "F.Fab")
		)
		(fp_line
			(start -0.8636 -0.4064)
			(end -0.8636 -0.4572)
			(stroke
				(width 0.1)
				(type default)
			)
			(layer "F.Fab")
		)
		(fp_line
			(start 0.8636 -0.4064)
			(end 1.1938 -0.4064)
			(stroke
				(width 0.1)
				(type default)
			)
			(layer "F.Fab")
		)
		(fp_line
			(start 1.1938 -0.4064)
			(end 1.1938 0.4064)
			(stroke
				(width 0.1)
				(type default)
			)
			(layer "F.Fab")
		)
		(fp_line
			(start -0.8636 -0.4572)
			(end 0.8636 -0.4572)
			(stroke
				(width 0.1)
				(type default)
			)
			(layer "F.Fab")
		)
		(fp_line
			(start 0.8636 -0.4572)
			(end 0.8636 -0.4064)
			(stroke
				(width 0.1)
				(type default)
			)
			(layer "F.Fab")
		)
		(pad "1" smd rect
			(at -0.7366 0 180)
			(size 0.7112 0.8128)
			(layers "F.Cu" "F.Mask" "F.Paste")
			(net "PVNN_TERM_CPU1")
		)
		(pad "2" smd rect
			(at 0.7366 0 180)
			(size 0.7112 0.8128)
			(layers "F.Cu" "F.Mask" "F.Paste")
			(net "GND")
		)
	)
)
